(kicad_pcb
	(version 20260206)
	(generator "pcbnew")
	(generator_version "10.0")
	(general
		(thickness 1.6)
		(legacy_teardrops no)
	)
	(paper "A4")
	(title_block
		(title "03242023_DA0F0TMBIJ0_F0T_Motherboard_J_brd_V01_OCP.brd")
		(comment 1 "Grand Teton / footprints 4323-4329 of 6105")
	)
	(layers
		(0 "F.Cu" signal "TOP")
		(4 "In1.Cu" signal "GND")
		(6 "In2.Cu" signal "IN1")
		(8 "In3.Cu" signal "GND1")
		(10 "In4.Cu" signal "IN2")
		(12 "In5.Cu" signal "GND2")
		(14 "In6.Cu" signal "IN3")
		(16 "In7.Cu" signal "GND3")
		(18 "In8.Cu" signal "VCC")
		(20 "In9.Cu" signal "VCC1")
		(22 "In10.Cu" signal "GND4")
		(24 "In11.Cu" signal "IN4")
		(26 "In12.Cu" signal "GND5")
		(28 "In13.Cu" signal "IN5")
		(30 "In14.Cu" signal "GND6")
		(32 "In15.Cu" signal "IN6")
		(34 "In16.Cu" signal "GND7")
		(2 "B.Cu" signal "BOTTOM")
		(9 "F.Adhes" user "F.Adhesive")
		(11 "B.Adhes" user "B.Adhesive")
		(13 "F.Paste" user "Package Geometry/Pastemask Top")
		(15 "B.Paste" user "Package Geometry/Pastemask Bottom")
		(5 "F.SilkS" user "Ref Des/Silkscreen Top")
		(7 "B.SilkS" user "Ref Des/Silkscreen Bottom")
		(1 "F.Mask" user "Board Geometry/Soldermask Top")
		(3 "B.Mask" user "Board Geometry/Soldermask Bottom")
		(17 "Dwgs.User" user "User.Drawings")
		(19 "Cmts.User" user "User.Comments")
		(21 "Eco1.User" user "User.Eco1")
		(23 "Eco2.User" user "User.Eco2")
		(25 "Edge.Cuts" user "Board Geometry/Outline")
		(27 "Margin" user)
		(31 "F.CrtYd" user "Package Geometry/Place Bound Top")
		(29 "B.CrtYd" user "Package Geometry/Place Bound Bottom")
		(35 "F.Fab" user "Ref Des/Assembly Top")
		(33 "B.Fab" user "Ref Des/Assembly Bottom")
	)
	(footprint ""
		(layer "B.Cu")
		(at 362.380276 -333.73568 90)
		(property "Reference" "PC281_P0_3"
			(at 0 0 90)
			(layer "B.SilkS")
			(hide yes)
			(effects
				(font
					(size 1.27 1.27)
				)
				(justify mirror)
			)
		)
		(property "Value" ""
			(at 0 0 90)
			(layer "B.Fab")
			(effects
				(font
					(size 1.27 1.27)
				)
				(justify mirror)
			)
		)
		(duplicate_pad_numbers_are_jumpers no)
		(fp_line
			(start 1.524 -0.762)
			(end -1.524 -0.762)
			(stroke
				(width 0.1524)
				(type default)
			)
			(layer "B.SilkS")
		)
		(fp_line
			(start -1.524 -0.762)
			(end -1.524 0.762)
			(stroke
				(width 0.1524)
				(type default)
			)
			(layer "B.SilkS")
		)
		(fp_line
			(start 1.524 0.762)
			(end 1.524 -0.762)
			(stroke
				(width 0.1524)
				(type default)
			)
			(layer "B.SilkS")
		)
		(fp_line
			(start -1.524 0.762)
			(end 1.524 0.762)
			(stroke
				(width 0.1524)
				(type default)
			)
			(layer "B.SilkS")
		)
		(fp_line
			(start 1.1049 -0.724916)
			(end 1.1049 0.724916)
			(stroke
				(width 0.1)
				(type default)
			)
			(layer "B.Fab")
		)
		(fp_line
			(start -1.1049 -0.724916)
			(end 1.1049 -0.724916)
			(stroke
				(width 0.1)
				(type default)
			)
			(layer "B.Fab")
		)
		(fp_line
			(start 1.1049 0.724916)
			(end -1.1049 0.724916)
			(stroke
				(width 0.1)
				(type default)
			)
			(layer "B.Fab")
		)
		(fp_line
			(start -1.1049 0.724916)
			(end -1.1049 -0.724916)
			(stroke
				(width 0.1)
				(type default)
			)
			(layer "B.Fab")
		)
		(pad "1" smd rect
			(at 0.889 0 90)
			(size 1.016 1.27)
			(layers "B.Cu" "B.Mask" "B.Paste")
			(net "SW_P12V_PVCCIN_CPU0_FLT")
		)
		(pad "2" smd rect
			(at -0.889 0 90)
			(size 1.016 1.27)
			(layers "B.Cu" "B.Mask" "B.Paste")
			(net "GND")
		)
	)
	(footprint ""
		(layer "B.Cu")
		(at 187.88888 -103.723948 180)
		(property "Reference" "C1937"
			(at 0 0 0)
			(layer "B.SilkS")
			(hide yes)
			(effects
				(font
					(size 1.27 1.27)
				)
				(justify mirror)
			)
		)
		(property "Value" ""
			(at 0 0 0)
			(layer "B.Fab")
			(effects
				(font
					(size 1.27 1.27)
				)
				(justify mirror)
			)
		)
		(duplicate_pad_numbers_are_jumpers no)
		(fp_line
			(start 0.7874 0.4064)
			(end 0.7874 -0.4064)
			(stroke
				(width 0.1524)
				(type default)
			)
			(layer "B.SilkS")
		)
		(fp_line
			(start 0.7874 -0.4064)
			(end -0.7874 -0.4064)
			(stroke
				(width 0.1524)
				(type default)
			)
			(layer "B.SilkS")
		)
		(fp_line
			(start -0.7874 0.4064)
			(end 0.7874 0.4064)
			(stroke
				(width 0.1524)
				(type default)
			)
			(layer "B.SilkS")
		)
		(fp_line
			(start -0.7874 -0.4064)
			(end -0.7874 0.4064)
			(stroke
				(width 0.1524)
				(type default)
			)
			(layer "B.SilkS")
		)
		(fp_line
			(start 0.67945 0.3048)
			(end 0.67945 -0.305054)
			(stroke
				(width 0.1)
				(type default)
			)
			(layer "B.Fab")
		)
		(fp_line
			(start 0.67945 -0.305054)
			(end 0.12065 -0.305054)
			(stroke
				(width 0.1)
				(type default)
			)
			(layer "B.Fab")
		)
		(fp_line
			(start 0.12065 0.3048)
			(end 0.67945 0.3048)
			(stroke
				(width 0.1)
				(type default)
			)
			(layer "B.Fab")
		)
		(fp_line
			(start 0.12065 0.2794)
			(end 0.12065 0.3048)
			(stroke
				(width 0.1)
				(type default)
			)
			(layer "B.Fab")
		)
		(fp_line
			(start 0.12065 -0.2794)
			(end -0.12065 -0.2794)
			(stroke
				(width 0.1)
				(type default)
			)
			(layer "B.Fab")
		)
		(fp_line
			(start 0.12065 -0.305054)
			(end 0.12065 -0.2794)
			(stroke
				(width 0.1)
				(type default)
			)
			(layer "B.Fab")
		)
		(fp_line
			(start -0.120396 0.3048)
			(end -0.120396 0.2794)
			(stroke
				(width 0.1)
				(type default)
			)
			(layer "B.Fab")
		)
		(fp_line
			(start -0.120396 0.2794)
			(end 0.12065 0.2794)
			(stroke
				(width 0.1)
				(type default)
			)
			(layer "B.Fab")
		)
		(fp_line
			(start -0.12065 -0.2794)
			(end -0.12065 -0.3048)
			(stroke
				(width 0.1)
				(type default)
			)
			(layer "B.Fab")
		)
		(fp_line
			(start -0.12065 -0.3048)
			(end -0.67945 -0.3048)
			(stroke
				(width 0.1)
				(type default)
			)
			(layer "B.Fab")
		)
		(fp_line
			(start -0.67945 0.3048)
			(end -0.120396 0.3048)
			(stroke
				(width 0.1)
				(type default)
			)
			(layer "B.Fab")
		)
		(fp_line
			(start -0.67945 -0.3048)
			(end -0.67945 0.3048)
			(stroke
				(width 0.1)
				(type default)
			)
			(layer "B.Fab")
		)
		(pad "1" smd circle
			(at 0.40005 0)
			(size 0 0)
			(layers "B.Cu" "B.Mask" "B.Paste")
			(net "P3V3_AUX_FPGA_VCCIO2")
		)
		(pad "2" smd circle
			(at -0.40005 0)
			(size 0 0)
			(layers "B.Cu" "B.Mask" "B.Paste")
			(net "GND")
		)
	)
	(footprint ""
		(layer "B.Cu")
		(at 365.82604 -398.976088)
		(property "Reference" "C1708"
			(at 0 0 0)
			(layer "B.SilkS")
			(hide yes)
			(effects
				(font
					(size 1.27 1.27)
				)
				(justify mirror)
			)
		)
		(property "Value" ""
			(at 0 0 0)
			(layer "B.Fab")
			(effects
				(font
					(size 1.27 1.27)
				)
				(justify mirror)
			)
		)
		(duplicate_pad_numbers_are_jumpers no)
		(fp_line
			(start -0.7874 -0.4064)
			(end -0.7874 0.4064)
			(stroke
				(width 0.1524)
				(type default)
			)
			(layer "B.SilkS")
		)
		(fp_line
			(start -0.7874 0.4064)
			(end 0.7874 0.4064)
			(stroke
				(width 0.1524)
				(type default)
			)
			(layer "B.SilkS")
		)
		(fp_line
			(start 0.7874 -0.4064)
			(end -0.7874 -0.4064)
			(stroke
				(width 0.1524)
				(type default)
			)
			(layer "B.SilkS")
		)
		(fp_line
			(start 0.7874 0.4064)
			(end 0.7874 -0.4064)
			(stroke
				(width 0.1524)
				(type default)
			)
			(layer "B.SilkS")
		)
		(fp_line
			(start -0.67945 -0.3048)
			(end -0.67945 0.3048)
			(stroke
				(width 0.1)
				(type default)
			)
			(layer "B.Fab")
		)
		(fp_line
			(start -0.67945 0.3048)
			(end -0.120396 0.3048)
			(stroke
				(width 0.1)
				(type default)
			)
			(layer "B.Fab")
		)
		(fp_line
			(start -0.12065 -0.3048)
			(end -0.67945 -0.3048)
			(stroke
				(width 0.1)
				(type default)
			)
			(layer "B.Fab")
		)
		(fp_line
			(start -0.12065 -0.2794)
			(end -0.12065 -0.3048)
			(stroke
				(width 0.1)
				(type default)
			)
			(layer "B.Fab")
		)
		(fp_line
			(start -0.120396 0.2794)
			(end 0.12065 0.2794)
			(stroke
				(width 0.1)
				(type default)
			)
			(layer "B.Fab")
		)
		(fp_line
			(start -0.120396 0.3048)
			(end -0.120396 0.2794)
			(stroke
				(width 0.1)
				(type default)
			)
			(layer "B.Fab")
		)
		(fp_line
			(start 0.12065 -0.305054)
			(end 0.12065 -0.2794)
			(stroke
				(width 0.1)
				(type default)
			)
			(layer "B.Fab")
		)
		(fp_line
			(start 0.12065 -0.2794)
			(end -0.12065 -0.2794)
			(stroke
				(width 0.1)
				(type default)
			)
			(layer "B.Fab")
		)
		(fp_line
			(start 0.12065 0.2794)
			(end 0.12065 0.3048)
			(stroke
				(width 0.1)
				(type default)
			)
			(layer "B.Fab")
		)
		(fp_line
			(start 0.12065 0.3048)
			(end 0.67945 0.3048)
			(stroke
				(width 0.1)
				(type default)
			)
			(layer "B.Fab")
		)
		(fp_line
			(start 0.67945 -0.305054)
			(end 0.12065 -0.305054)
			(stroke
				(width 0.1)
				(type default)
			)
			(layer "B.Fab")
		)
		(fp_line
			(start 0.67945 0.3048)
			(end 0.67945 -0.305054)
			(stroke
				(width 0.1)
				(type default)
			)
			(layer "B.Fab")
		)
		(pad "1" smd circle
			(at 0.40005 0 180)
			(size 0 0)
			(layers "B.Cu" "B.Mask" "B.Paste")
			(net "P3V3_AUX")
		)
		(pad "2" smd circle
			(at -0.40005 0 180)
			(size 0 0)
			(layers "B.Cu" "B.Mask" "B.Paste")
			(net "GND")
		)
	)
	(footprint ""
		(layer "B.Cu")
		(at 39.062406 -354.565204 -90)
		(property "Reference" "PR1307"
			(at 0 0 90)
			(layer "B.SilkS")
			(hide yes)
			(effects
				(font
					(size 1.27 1.27)
				)
				(justify mirror)
			)
		)
		(property "Value" ""
			(at 0 0 90)
			(layer "B.Fab")
			(effects
				(font
					(size 1.27 1.27)
				)
				(justify mirror)
			)
		)
		(duplicate_pad_numbers_are_jumpers no)
		(fp_line
			(start -0.7874 0.4064)
			(end 0.7874 0.4064)
			(stroke
				(width 0.1524)
				(type default)
			)
			(layer "B.SilkS")
		)
		(fp_line
			(start 0.7874 0.4064)
			(end 0.7874 -0.4064)
			(stroke
				(width 0.1524)
				(type default)
			)
			(layer "B.SilkS")
		)
		(fp_line
			(start -0.7874 -0.4064)
			(end -0.7874 0.4064)
			(stroke
				(width 0.1524)
				(type default)
			)
			(layer "B.SilkS")
		)
		(fp_line
			(start 0.7874 -0.4064)
			(end -0.7874 -0.4064)
			(stroke
				(width 0.1524)
				(type default)
			)
			(layer "B.SilkS")
		)
		(fp_line
			(start -0.67945 0.3048)
			(end -0.120396 0.3048)
			(stroke
				(width 0.1)
				(type default)
			)
			(layer "B.Fab")
		)
		(fp_line
			(start -0.120396 0.3048)
			(end -0.120396 0.2794)
			(stroke
				(width 0.1)
				(type default)
			)
			(layer "B.Fab")
		)
		(fp_line
			(start 0.12065 0.3048)
			(end 0.67945 0.3048)
			(stroke
				(width 0.1)
				(type default)
			)
			(layer "B.Fab")
		)
		(fp_line
			(start 0.67945 0.3048)
			(end 0.67945 -0.305054)
			(stroke
				(width 0.1)
				(type default)
			)
			(layer "B.Fab")
		)
		(fp_line
			(start -0.120396 0.2794)
			(end 0.12065 0.2794)
			(stroke
				(width 0.1)
				(type default)
			)
			(layer "B.Fab")
		)
		(fp_line
			(start 0.12065 0.2794)
			(end 0.12065 0.3048)
			(stroke
				(width 0.1)
				(type default)
			)
			(layer "B.Fab")
		)
		(fp_line
			(start -0.12065 -0.2794)
			(end -0.12065 -0.3048)
			(stroke
				(width 0.1)
				(type default)
			)
			(layer "B.Fab")
		)
		(fp_line
			(start 0.12065 -0.2794)
			(end -0.12065 -0.2794)
			(stroke
				(width 0.1)
				(type default)
			)
			(layer "B.Fab")
		)
		(fp_line
			(start -0.67945 -0.3048)
			(end -0.67945 0.3048)
			(stroke
				(width 0.1)
				(type default)
			)
			(layer "B.Fab")
		)
		(fp_line
			(start -0.12065 -0.3048)
			(end -0.67945 -0.3048)
			(stroke
				(width 0.1)
				(type default)
			)
			(layer "B.Fab")
		)
		(fp_line
			(start 0.12065 -0.305054)
			(end 0.12065 -0.2794)
			(stroke
				(width 0.1)
				(type default)
			)
			(layer "B.Fab")
		)
		(fp_line
			(start 0.67945 -0.305054)
			(end 0.12065 -0.305054)
			(stroke
				(width 0.1)
				(type default)
			)
			(layer "B.Fab")
		)
		(pad "1" smd circle
			(at 0.40005 0 90)
			(size 0 0)
			(layers "B.Cu" "B.Mask" "B.Paste")
			(net "PVCCFA_EHV_FIVRA_CPU1_PVCC2")
		)
		(pad "2" smd circle
			(at -0.40005 0 90)
			(size 0 0)
			(layers "B.Cu" "B.Mask" "B.Paste")
			(net "PVCCFA_EHV_FIVRA_CPU1_VDD4")
		)
	)
	(footprint ""
		(layer "B.Cu")
		(at 114.734086 -212.049868 180)
		(property "Reference" "C467"
			(at 0 0 0)
			(layer "B.SilkS")
			(hide yes)
			(effects
				(font
					(size 1.27 1.27)
				)
				(justify mirror)
			)
		)
		(property "Value" ""
			(at 0 0 0)
			(layer "B.Fab")
			(effects
				(font
					(size 1.27 1.27)
				)
				(justify mirror)
			)
		)
		(duplicate_pad_numbers_are_jumpers no)
		(fp_line
			(start 1.524 0.762)
			(end 1.524 -0.762)
			(stroke
				(width 0.1524)
				(type default)
			)
			(layer "B.SilkS")
		)
		(fp_line
			(start 1.524 -0.762)
			(end -1.524 -0.762)
			(stroke
				(width 0.1524)
				(type default)
			)
			(layer "B.SilkS")
		)
		(fp_line
			(start -1.524 0.762)
			(end 1.524 0.762)
			(stroke
				(width 0.1524)
				(type default)
			)
			(layer "B.SilkS")
		)
		(fp_line
			(start -1.524 -0.762)
			(end -1.524 0.762)
			(stroke
				(width 0.1524)
				(type default)
			)
			(layer "B.SilkS")
		)
		(fp_line
			(start 1.1049 0.724916)
			(end -1.1049 0.724916)
			(stroke
				(width 0.1)
				(type default)
			)
			(layer "B.Fab")
		)
		(fp_line
			(start 1.1049 -0.724916)
			(end 1.1049 0.724916)
			(stroke
				(width 0.1)
				(type default)
			)
			(layer "B.Fab")
		)
		(fp_line
			(start -1.1049 0.724916)
			(end -1.1049 -0.724916)
			(stroke
				(width 0.1)
				(type default)
			)
			(layer "B.Fab")
		)
		(fp_line
			(start -1.1049 -0.724916)
			(end 1.1049 -0.724916)
			(stroke
				(width 0.1)
				(type default)
			)
			(layer "B.Fab")
		)
		(pad "1" smd rect
			(at 0.889 0 180)
			(size 1.016 1.27)
			(layers "B.Cu" "B.Mask" "B.Paste")
			(net "PVCCD_HV_CPU1")
		)
		(pad "2" smd rect
			(at -0.889 0 180)
			(size 1.016 1.27)
			(layers "B.Cu" "B.Mask" "B.Paste")
			(net "GND")
		)
	)
	(footprint ""
		(layer "B.Cu")
		(at 122.794268 -337.546442 -90)
		(property "Reference" "PC533_P1_4"
			(at 0 0 90)
			(layer "B.SilkS")
			(hide yes)
			(effects
				(font
					(size 1.27 1.27)
				)
				(justify mirror)
			)
		)
		(property "Value" ""
			(at 0 0 90)
			(layer "B.Fab")
			(effects
				(font
					(size 1.27 1.27)
				)
				(justify mirror)
			)
		)
		(duplicate_pad_numbers_are_jumpers no)
		(fp_line
			(start -1.524 0.762)
			(end 1.524 0.762)
			(stroke
				(width 0.1524)
				(type default)
			)
			(layer "B.SilkS")
		)
		(fp_line
			(start 1.524 0.762)
			(end 1.524 -0.762)
			(stroke
				(width 0.1524)
				(type default)
			)
			(layer "B.SilkS")
		)
		(fp_line
			(start -1.524 -0.762)
			(end -1.524 0.762)
			(stroke
				(width 0.1524)
				(type default)
			)
			(layer "B.SilkS")
		)
		(fp_line
			(start 1.524 -0.762)
			(end -1.524 -0.762)
			(stroke
				(width 0.1524)
				(type default)
			)
			(layer "B.SilkS")
		)
		(fp_line
			(start -1.1049 0.724916)
			(end -1.1049 -0.724916)
			(stroke
				(width 0.1)
				(type default)
			)
			(layer "B.Fab")
		)
		(fp_line
			(start 1.1049 0.724916)
			(end -1.1049 0.724916)
			(stroke
				(width 0.1)
				(type default)
			)
			(layer "B.Fab")
		)
		(fp_line
			(start -1.1049 -0.724916)
			(end 1.1049 -0.724916)
			(stroke
				(width 0.1)
				(type default)
			)
			(layer "B.Fab")
		)
		(fp_line
			(start 1.1049 -0.724916)
			(end 1.1049 0.724916)
			(stroke
				(width 0.1)
				(type default)
			)
			(layer "B.Fab")
		)
		(pad "1" smd rect
			(at 0.889 0 270)
			(size 1.016 1.27)
			(layers "B.Cu" "B.Mask" "B.Paste")
			(net "SW_P12V_PVCCIN_CPU1_FLT")
		)
		(pad "2" smd rect
			(at -0.889 0 270)
			(size 1.016 1.27)
			(layers "B.Cu" "B.Mask" "B.Paste")
			(net "GND")
		)
	)
	(footprint ""
		(layer "B.Cu")
		(at 61.25464 -316.608968 90)
		(property "Reference" "R894"
			(at 0 0 90)
			(layer "B.SilkS")
			(hide yes)
			(effects
				(font
					(size 1.27 1.27)
				)
				(justify mirror)
			)
		)
		(property "Value" ""
			(at 0 0 90)
			(layer "B.Fab")
			(effects
				(font
					(size 1.27 1.27)
				)
				(justify mirror)
			)
		)
		(duplicate_pad_numbers_are_jumpers no)
		(fp_line
			(start 0.7874 -0.4064)
			(end -0.7874 -0.4064)
			(stroke
				(width 0.1524)
				(type default)
			)
			(layer "B.SilkS")
		)
		(fp_line
			(start -0.7874 -0.4064)
			(end -0.7874 0.4064)
			(stroke
				(width 0.1524)
				(type default)
			)
			(layer "B.SilkS")
		)
		(fp_line
			(start 0.7874 0.4064)
			(end 0.7874 -0.4064)
			(stroke
				(width 0.1524)
				(type default)
			)
			(layer "B.SilkS")
		)
		(fp_line
			(start -0.7874 0.4064)
			(end 0.7874 0.4064)
			(stroke
				(width 0.1524)
				(type default)
			)
			(layer "B.SilkS")
		)
		(fp_line
			(start 0.67945 -0.305054)
			(end 0.12065 -0.305054)
			(stroke
				(width 0.1)
				(type default)
			)
			(layer "B.Fab")
		)
		(fp_line
			(start 0.12065 -0.305054)
			(end 0.12065 -0.2794)
			(stroke
				(width 0.1)
				(type default)
			)
			(layer "B.Fab")
		)
		(fp_line
			(start -0.12065 -0.3048)
			(end -0.67945 -0.3048)
			(stroke
				(width 0.1)
				(type default)
			)
			(layer "B.Fab")
		)
		(fp_line
			(start -0.67945 -0.3048)
			(end -0.67945 0.3048)
			(stroke
				(width 0.1)
				(type default)
			)
			(layer "B.Fab")
		)
		(fp_line
			(start 0.12065 -0.2794)
			(end -0.12065 -0.2794)
			(stroke
				(width 0.1)
				(type default)
			)
			(layer "B.Fab")
		)
		(fp_line
			(start -0.12065 -0.2794)
			(end -0.12065 -0.3048)
			(stroke
				(width 0.1)
				(type default)
			)
			(layer "B.Fab")
		)
		(fp_line
			(start 0.12065 0.2794)
			(end 0.12065 0.3048)
			(stroke
				(width 0.1)
				(type default)
			)
			(layer "B.Fab")
		)
		(fp_line
			(start -0.120396 0.2794)
			(end 0.12065 0.2794)
			(stroke
				(width 0.1)
				(type default)
			)
			(layer "B.Fab")
		)
		(fp_line
			(start 0.67945 0.3048)
			(end 0.67945 -0.305054)
			(stroke
				(width 0.1)
				(type default)
			)
			(layer "B.Fab")
		)
		(fp_line
			(start 0.12065 0.3048)
			(end 0.67945 0.3048)
			(stroke
				(width 0.1)
				(type default)
			)
			(layer "B.Fab")
		)
		(fp_line
			(start -0.120396 0.3048)
			(end -0.120396 0.2794)
			(stroke
				(width 0.1)
				(type default)
			)
			(layer "B.Fab")
		)
		(fp_line
			(start -0.67945 0.3048)
			(end -0.120396 0.3048)
			(stroke
				(width 0.1)
				(type default)
			)
			(layer "B.Fab")
		)
		(pad "1" smd circle
			(at 0.40005 0 270)
			(size 0 0)
			(layers "B.Cu" "B.Mask" "B.Paste")
			(net "PWRGD_CHA_CPU1_DIMM2")
		)
		(pad "2" smd circle
			(at -0.40005 0 270)
			(size 0 0)
			(layers "B.Cu" "B.Mask" "B.Paste")
			(net "PWRGD_FAIL_CPU1_AB")
		)
	)
)
